# S9S_MB_2U (Grand Teton) — schematic netlist excerpt (pin names and nets, part order shuffled) for the footprints in the layout excerpt that follows; sources: Cadence DE-HDL packaged netlist, KiCad conversion of 03242023_DA0F0TMBIJ0_F0T_Motherboard_J_brd_V01_OCP.brd

R1184  Q_RES  0 5% CHIP  pkg 0402LF  page 239 : A = JTAG_BMC_DBP_TMS_R ; B = JTAG_BMC_DBP_TMS
C270  Q_CAP  47UF 4V 20% X6S  pkg C0805  page 77 : A = PVCCIN_CPU1 ; B = GND
PR4223  Q_RES  0 5% CHIP  pkg 0402LF  page 274 : A = NC_PVCCINFAON_CPU0_ACSP5 ; B = GND

(kicad_pcb
	(version 20260206)
	(generator "pcbnew")
	(generator_version "10.0")
	(general
		(thickness 1.6)
		(legacy_teardrops no)
	)
	(paper "A4")
	(title_block
		(title "03242023_DA0F0TMBIJ0_F0T_Motherboard_J_brd_V01_OCP.brd")
		(comment 1 "Grand Teton / footprints 3358-3360 of 6105")
	)
	(layers
		(0 "F.Cu" signal "TOP")
		(4 "In1.Cu" signal "GND")
		(6 "In2.Cu" signal "IN1")
		(8 "In3.Cu" signal "GND1")
		(10 "In4.Cu" signal "IN2")
		(12 "In5.Cu" signal "GND2")
		(14 "In6.Cu" signal "IN3")
		(16 "In7.Cu" signal "GND3")
		(18 "In8.Cu" signal "VCC")
		(20 "In9.Cu" signal "VCC1")
		(22 "In10.Cu" signal "GND4")
		(24 "In11.Cu" signal "IN4")
		(26 "In12.Cu" signal "GND5")
		(28 "In13.Cu" signal "IN5")
		(30 "In14.Cu" signal "GND6")
		(32 "In15.Cu" signal "IN6")
		(34 "In16.Cu" signal "GND7")
		(2 "B.Cu" signal "BOTTOM")
		(9 "F.Adhes" user "F.Adhesive")
		(11 "B.Adhes" user "B.Adhesive")
		(13 "F.Paste" user "Package Geometry/Pastemask Top")
		(15 "B.Paste" user "Package Geometry/Pastemask Bottom")
		(5 "F.SilkS" user "Ref Des/Silkscreen Top")
		(7 "B.SilkS" user "Ref Des/Silkscreen Bottom")
		(1 "F.Mask" user "Board Geometry/Soldermask Top")
		(3 "B.Mask" user "Board Geometry/Soldermask Bottom")
		(17 "Dwgs.User" user "User.Drawings")
		(19 "Cmts.User" user "User.Comments")
		(21 "Eco1.User" user "User.Eco1")
		(23 "Eco2.User" user "User.Eco2")
		(25 "Edge.Cuts" user "Board Geometry/Outline")
		(27 "Margin" user)
		(31 "F.CrtYd" user "Package Geometry/Place Bound Top")
		(29 "B.CrtYd" user "Package Geometry/Place Bound Bottom")
		(35 "F.Fab" user "Ref Des/Assembly Top")
		(33 "B.Fab" user "Ref Des/Assembly Bottom")
	)
	(footprint ""
		(layer "F.Cu")
		(at 424.69816 -143.675608 90)
		(property "Reference" "PR4223"
			(at 0 0 90)
			(layer "F.SilkS")
			(hide yes)
			(effects
				(font
					(size 1.27 1.27)
				)
			)
		)
		(property "Value" ""
			(at 0 0 90)
			(layer "F.Fab")
			(effects
				(font
					(size 1.27 1.27)
				)
			)
		)
		(duplicate_pad_numbers_are_jumpers no)
		(fp_line
			(start 0.7874 -0.4064)
			(end 0.7874 0.4064)
			(stroke
				(width 0.1524)
				(type default)
			)
			(layer "F.SilkS")
		)
		(fp_line
			(start -0.7874 -0.4064)
			(end 0.7874 -0.4064)
			(stroke
				(width 0.1524)
				(type default)
			)
			(layer "F.SilkS")
		)
		(fp_line
			(start 0.7874 0.4064)
			(end -0.7874 0.4064)
			(stroke
				(width 0.1524)
				(type default)
			)
			(layer "F.SilkS")
		)
		(fp_line
			(start -0.7874 0.4064)
			(end -0.7874 -0.4064)
			(stroke
				(width 0.1524)
				(type default)
			)
			(layer "F.SilkS")
		)
		(fp_line
			(start -0.12065 -0.305054)
			(end -0.12065 -0.2794)
			(stroke
				(width 0.1)
				(type default)
			)
			(layer "F.Fab")
		)
		(fp_line
			(start -0.67945 -0.305054)
			(end -0.12065 -0.305054)
			(stroke
				(width 0.1)
				(type default)
			)
			(layer "F.Fab")
		)
		(fp_line
			(start 0.67945 -0.3048)
			(end 0.67945 0.3048)
			(stroke
				(width 0.1)
				(type default)
			)
			(layer "F.Fab")
		)
		(fp_line
			(start 0.12065 -0.3048)
			(end 0.67945 -0.3048)
			(stroke
				(width 0.1)
				(type default)
			)
			(layer "F.Fab")
		)
		(fp_line
			(start 0.12065 -0.2794)
			(end 0.12065 -0.3048)
			(stroke
				(width 0.1)
				(type default)
			)
			(layer "F.Fab")
		)
		(fp_line
			(start -0.12065 -0.2794)
			(end 0.12065 -0.2794)
			(stroke
				(width 0.1)
				(type default)
			)
			(layer "F.Fab")
		)
		(fp_line
			(start 0.120396 0.2794)
			(end -0.12065 0.2794)
			(stroke
				(width 0.1)
				(type default)
			)
			(layer "F.Fab")
		)
		(fp_line
			(start -0.12065 0.2794)
			(end -0.12065 0.3048)
			(stroke
				(width 0.1)
				(type default)
			)
			(layer "F.Fab")
		)
		(fp_line
			(start 0.67945 0.3048)
			(end 0.120396 0.3048)
			(stroke
				(width 0.1)
				(type default)
			)
			(layer "F.Fab")
		)
		(fp_line
			(start 0.120396 0.3048)
			(end 0.120396 0.2794)
			(stroke
				(width 0.1)
				(type default)
			)
			(layer "F.Fab")
		)
		(fp_line
			(start -0.12065 0.3048)
			(end -0.67945 0.3048)
			(stroke
				(width 0.1)
				(type default)
			)
			(layer "F.Fab")
		)
		(fp_line
			(start -0.67945 0.3048)
			(end -0.67945 -0.305054)
			(stroke
				(width 0.1)
				(type default)
			)
			(layer "F.Fab")
		)
		(pad "1" smd circle
			(at -0.40005 0 90)
			(size 0 0)
			(layers "F.Cu" "F.Mask" "F.Paste")
			(net "NC_PVCCINFAON_CPU0_ACSP5")
		)
		(pad "2" smd circle
			(at 0.40005 0 90)
			(size 0 0)
			(layers "F.Cu" "F.Mask" "F.Paste")
			(net "GND")
		)
	)
	(footprint ""
		(layer "F.Cu")
		(at 118.09222 -294.01008 180)
		(property "Reference" "C270"
			(at 0 0 180)
			(layer "F.SilkS")
			(hide yes)
			(effects
				(font
					(size 1.27 1.27)
				)
			)
		)
		(property "Value" ""
			(at 0 0 180)
			(layer "F.Fab")
			(effects
				(font
					(size 1.27 1.27)
				)
			)
		)
		(duplicate_pad_numbers_are_jumpers no)
		(fp_line
			(start 1.524 0.762)
			(end -1.524 0.762)
			(stroke
				(width 0.1524)
				(type default)
			)
			(layer "F.SilkS")
		)
		(fp_line
			(start 1.524 -0.762)
			(end 1.524 0.762)
			(stroke
				(width 0.1524)
				(type default)
			)
			(layer "F.SilkS")
		)
		(fp_line
			(start -1.524 0.762)
			(end -1.524 -0.762)
			(stroke
				(width 0.1524)
				(type default)
			)
			(layer "F.SilkS")
		)
		(fp_line
			(start -1.524 -0.762)
			(end 1.524 -0.762)
			(stroke
				(width 0.1524)
				(type default)
			)
			(layer "F.SilkS")
		)
		(fp_line
			(start 1.1049 0.724916)
			(end 1.1049 -0.724916)
			(stroke
				(width 0.1)
				(type default)
			)
			(layer "F.Fab")
		)
		(fp_line
			(start 1.1049 -0.724916)
			(end -1.1049 -0.724916)
			(stroke
				(width 0.1)
				(type default)
			)
			(layer "F.Fab")
		)
		(fp_line
			(start -1.1049 0.724916)
			(end 1.1049 0.724916)
			(stroke
				(width 0.1)
				(type default)
			)
			(layer "F.Fab")
		)
		(fp_line
			(start -1.1049 -0.724916)
			(end -1.1049 0.724916)
			(stroke
				(width 0.1)
				(type default)
			)
			(layer "F.Fab")
		)
		(pad "1" smd rect
			(at -0.889 0)
			(size 1.016 1.27)
			(layers "F.Cu" "F.Mask" "F.Paste")
			(net "PVCCIN_CPU1")
		)
		(pad "2" smd rect
			(at 0.889 0)
			(size 1.016 1.27)
			(layers "F.Cu" "F.Mask" "F.Paste")
			(net "GND")
		)
	)
	(footprint ""
		(layer "F.Cu")
		(at 123.317 -75.021948 90)
		(property "Reference" "R1184"
			(at 0 0 90)
			(layer "F.SilkS")
			(hide yes)
			(effects
				(font
					(size 1.27 1.27)
				)
			)
		)
		(property "Value" ""
			(at 0 0 90)
			(layer "F.Fab")
			(effects
				(font
					(size 1.27 1.27)
				)
			)
		)
		(duplicate_pad_numbers_are_jumpers no)
		(fp_line
			(start 0.7874 -0.4064)
			(end 0.7874 0.4064)
			(stroke
				(width 0.1524)
				(type default)
			)
			(layer "F.SilkS")
		)
		(fp_line
			(start -0.7874 -0.4064)
			(end 0.7874 -0.4064)
			(stroke
				(width 0.1524)
				(type default)
			)
			(layer "F.SilkS")
		)
		(fp_line
			(start 0.7874 0.4064)
			(end -0.7874 0.4064)
			(stroke
				(width 0.1524)
				(type default)
			)
			(layer "F.SilkS")
		)
		(fp_line
			(start -0.7874 0.4064)
			(end -0.7874 -0.4064)
			(stroke
				(width 0.1524)
				(type default)
			)
			(layer "F.SilkS")
		)
		(fp_line
			(start -0.12065 -0.305054)
			(end -0.12065 -0.2794)
			(stroke
				(width 0.1)
				(type default)
			)
			(layer "F.Fab")
		)
		(fp_line
			(start -0.67945 -0.305054)
			(end -0.12065 -0.305054)
			(stroke
				(width 0.1)
				(type default)
			)
			(layer "F.Fab")
		)
		(fp_line
			(start 0.67945 -0.3048)
			(end 0.67945 0.3048)
			(stroke
				(width 0.1)
				(type default)
			)
			(layer "F.Fab")
		)
		(fp_line
			(start 0.12065 -0.3048)
			(end 0.67945 -0.3048)
			(stroke
				(width 0.1)
				(type default)
			)
			(layer "F.Fab")
		)
		(fp_line
			(start 0.12065 -0.2794)
			(end 0.12065 -0.3048)
			(stroke
				(width 0.1)
				(type default)
			)
			(layer "F.Fab")
		)
		(fp_line
			(start -0.12065 -0.2794)
			(end 0.12065 -0.2794)
			(stroke
				(width 0.1)
				(type default)
			)
			(layer "F.Fab")
		)
		(fp_line
			(start 0.120396 0.2794)
			(end -0.12065 0.2794)
			(stroke
				(width 0.1)
				(type default)
			)
			(layer "F.Fab")
		)
		(fp_line
			(start -0.12065 0.2794)
			(end -0.12065 0.3048)
			(stroke
				(width 0.1)
				(type default)
			)
			(layer "F.Fab")
		)
		(fp_line
			(start 0.67945 0.3048)
			(end 0.120396 0.3048)
			(stroke
				(width 0.1)
				(type default)
			)
			(layer "F.Fab")
		)
		(fp_line
			(start 0.120396 0.3048)
			(end 0.120396 0.2794)
			(stroke
				(width 0.1)
				(type default)
			)
			(layer "F.Fab")
		)
		(fp_line
			(start -0.12065 0.3048)
			(end -0.67945 0.3048)
			(stroke
				(width 0.1)
				(type default)
			)
			(layer "F.Fab")
		)
		(fp_line
			(start -0.67945 0.3048)
			(end -0.67945 -0.305054)
			(stroke
				(width 0.1)
				(type default)
			)
			(layer "F.Fab")
		)
		(pad "1" smd circle
			(at -0.40005 0 90)
			(size 0 0)
			(layers "F.Cu" "F.Mask" "F.Paste")
			(net "JTAG_BMC_DBP_TMS_R")
		)
		(pad "2" smd circle
			(at 0.40005 0 90)
			(size 0 0)
			(layers "F.Cu" "F.Mask" "F.Paste")
			(net "JTAG_BMC_DBP_TMS")
		)
	)
)
